(kicad_pcb
	(version 20260206)
	(generator "pcbnew")
	(generator_version "10.0")
	(general
		(thickness 1.6)
		(legacy_teardrops no)
	)
	(paper "A4")
	(title_block
		(title "01162023_DA0F0TEBIF0_F0T_Expander_BD_F_brd_V02_OCP.brd")
		(comment 1 "Grand Teton / footprint 6619 of 9728 (PEX0), pads 595-712 of 2397")
	)
	(layers
		(0 "F.Cu" signal "TOP")
		(4 "In1.Cu" signal "GND")
		(6 "In2.Cu" signal "VCC")
		(8 "In3.Cu" signal "VCC1")
		(10 "In4.Cu" signal "GND1")
		(12 "In5.Cu" signal "IN1")
		(14 "In6.Cu" signal "GND2")
		(16 "In7.Cu" signal "IN2")
		(18 "In8.Cu" signal "GND3")
		(20 "In9.Cu" signal "IN3")
		(22 "In10.Cu" signal "GND4")
		(24 "In11.Cu" signal "IN4")
		(26 "In12.Cu" signal "GND5")
		(28 "In13.Cu" signal "IN5")
		(30 "In14.Cu" signal "GND6")
		(32 "In15.Cu" signal "IN6")
		(34 "In16.Cu" signal "GND7")
		(2 "B.Cu" signal "BOTTOM")
		(9 "F.Adhes" user "F.Adhesive")
		(11 "B.Adhes" user "B.Adhesive")
		(13 "F.Paste" user "Package Geometry/Pastemask Top")
		(15 "B.Paste" user "Package Geometry/Pastemask Bottom")
		(5 "F.SilkS" user "Ref Des/Silkscreen Top")
		(7 "B.SilkS" user "Ref Des/Silkscreen Bottom")
		(1 "F.Mask" user "Board Geometry/Soldermask Top")
		(3 "B.Mask" user "Board Geometry/Soldermask Bottom")
		(17 "Dwgs.User" user "User.Drawings")
		(19 "Cmts.User" user "User.Comments")
		(21 "Eco1.User" user "User.Eco1")
		(23 "Eco2.User" user "User.Eco2")
		(25 "Edge.Cuts" user "Board Geometry/Outline")
		(27 "Margin" user)
		(31 "F.CrtYd" user "Package Geometry/Place Bound Top")
		(29 "B.CrtYd" user "Package Geometry/Place Bound Bottom")
		(35 "F.Fab" user "Ref Des/Assembly Top")
		(33 "B.Fab" user "Ref Des/Assembly Bottom")
	)
	(footprint ""
		(layer "F.Cu")
		(at 59.649868 -295.89984)
		(property "Reference" "PEX0"
			(at -3.360166 35.566858 0)
			(unlocked yes)
			(layer "F.SilkS")
			(effects
				(font
					(size 2.032 1.524)
					(thickness 0.1524)
				)
				(justify left)
			)
		)
		(property "Value" ""
			(at 0 0 0)
			(layer "F.Fab")
			(effects
				(font
					(size 1.27 1.27)
				)
			)
		)
		(duplicate_pad_numbers_are_jumpers no)
		(pad "AM9" smd circle
			(at -15.200122 6.649974)
			(size 0.4572 0.4572)
			(layers "F.Cu" "F.Mask" "F.Paste")
			(net "P4E_PEX0_STN3_TX_DP<48>")
		)
		(pad "AM10" smd circle
			(at -14.249908 6.649974)
			(size 0.4572 0.4572)
			(layers "F.Cu" "F.Mask" "F.Paste")
			(net "GND")
		)
		(pad "AM11" smd circle
			(at -13.299948 6.649974)
			(size 0.4572 0.4572)
			(layers "F.Cu" "F.Mask" "F.Paste")
			(net "GND")
		)
		(pad "AM12" smd circle
			(at -12.349988 6.649974)
			(size 0.4572 0.4572)
			(layers "F.Cu" "F.Mask" "F.Paste")
			(net "TP_PEX0_VDDQ_EFUSE")
		)
		(pad "AM13" smd circle
			(at -11.400028 6.649974)
			(size 0.4572 0.4572)
			(layers "F.Cu" "F.Mask" "F.Paste")
			(net "GND")
		)
		(pad "AM14" smd circle
			(at -10.450068 6.649974)
			(size 0.4572 0.4572)
			(layers "F.Cu" "F.Mask" "F.Paste")
			(net "P1V8_VDDA_PEX0")
		)
		(pad "AM15" smd circle
			(at -9.500108 6.649974)
			(size 0.4572 0.4572)
			(layers "F.Cu" "F.Mask" "F.Paste")
			(net "GND")
		)
		(pad "AM16" smd circle
			(at -8.549894 6.649974)
			(size 0.4572 0.4572)
			(layers "F.Cu" "F.Mask" "F.Paste")
			(net "P1V25_PEX0")
		)
		(pad "AM17" smd circle
			(at -7.599934 6.649974)
			(size 0.4572 0.4572)
			(layers "F.Cu" "F.Mask" "F.Paste")
			(net "P1V25_PEX0")
		)
		(pad "AM18" smd circle
			(at -6.649974 6.649974)
			(size 0.4572 0.4572)
			(layers "F.Cu" "F.Mask" "F.Paste")
			(net "P1V25_PEX0")
		)
		(pad "AM19" smd circle
			(at -5.700014 6.649974)
			(size 0.4572 0.4572)
			(layers "F.Cu" "F.Mask" "F.Paste")
			(net "P1V25_PEX0")
		)
		(pad "AM20" smd circle
			(at -4.750054 6.649974)
			(size 0.4572 0.4572)
			(layers "F.Cu" "F.Mask" "F.Paste")
			(net "P1V25_PEX0")
		)
		(pad "AM21" smd circle
			(at -3.800094 6.649974)
			(size 0.4572 0.4572)
			(layers "F.Cu" "F.Mask" "F.Paste")
			(net "P1V25_PEX0")
		)
		(pad "AM22" smd circle
			(at -2.84988 6.649974)
			(size 0.4572 0.4572)
			(layers "F.Cu" "F.Mask" "F.Paste")
			(net "P1V25_PEX0")
		)
		(pad "AM23" smd circle
			(at -1.89992 6.649974)
			(size 0.4572 0.4572)
			(layers "F.Cu" "F.Mask" "F.Paste")
			(net "P1V25_PEX0")
		)
		(pad "AM24" smd circle
			(at -0.94996 6.649974)
			(size 0.4572 0.4572)
			(layers "F.Cu" "F.Mask" "F.Paste")
			(net "P1V25_PEX0")
		)
		(pad "AM25" smd circle
			(at 0 6.649974)
			(size 0.4572 0.4572)
			(layers "F.Cu" "F.Mask" "F.Paste")
			(net "P1V25_PEX0")
		)
		(pad "AM26" smd circle
			(at 0.94996 6.649974)
			(size 0.4572 0.4572)
			(layers "F.Cu" "F.Mask" "F.Paste")
			(net "P1V25_PEX0")
		)
		(pad "AM27" smd circle
			(at 1.89992 6.649974)
			(size 0.4572 0.4572)
			(layers "F.Cu" "F.Mask" "F.Paste")
			(net "P1V25_PEX0")
		)
		(pad "AM28" smd circle
			(at 2.84988 6.649974)
			(size 0.4572 0.4572)
			(layers "F.Cu" "F.Mask" "F.Paste")
			(net "P1V25_PEX0")
		)
		(pad "AM29" smd circle
			(at 3.800094 6.649974)
			(size 0.4572 0.4572)
			(layers "F.Cu" "F.Mask" "F.Paste")
			(net "P1V25_PEX0")
		)
		(pad "AM30" smd circle
			(at 4.750054 6.649974)
			(size 0.4572 0.4572)
			(layers "F.Cu" "F.Mask" "F.Paste")
			(net "P1V25_PEX0")
		)
		(pad "AM31" smd circle
			(at 5.700014 6.649974)
			(size 0.4572 0.4572)
			(layers "F.Cu" "F.Mask" "F.Paste")
			(net "P1V25_PEX0")
		)
		(pad "AM32" smd circle
			(at 6.649974 6.649974)
			(size 0.4572 0.4572)
			(layers "F.Cu" "F.Mask" "F.Paste")
			(net "P1V25_PEX0")
		)
		(pad "AM33" smd circle
			(at 7.599934 6.649974)
			(size 0.4572 0.4572)
			(layers "F.Cu" "F.Mask" "F.Paste")
			(net "P1V25_PEX0")
		)
		(pad "AM34" smd circle
			(at 8.549894 6.649974)
			(size 0.4572 0.4572)
			(layers "F.Cu" "F.Mask" "F.Paste")
			(net "GND")
		)
		(pad "AM35" smd circle
			(at 9.500108 6.649974)
			(size 0.4572 0.4572)
			(layers "F.Cu" "F.Mask" "F.Paste")
			(net "P1V8_PEX")
		)
		(pad "AM36" smd circle
			(at 10.450068 6.649974)
			(size 0.4572 0.4572)
			(layers "F.Cu" "F.Mask" "F.Paste")
			(net "GND")
		)
		(pad "AM37" smd circle
			(at 11.400028 6.649974)
			(size 0.4572 0.4572)
			(layers "F.Cu" "F.Mask" "F.Paste")
			(net "GND")
		)
		(pad "AM38" smd circle
			(at 12.349988 6.649974)
			(size 0.4572 0.4572)
			(layers "F.Cu" "F.Mask" "F.Paste")
			(net "Net_2844")
		)
		(pad "AM39" smd circle
			(at 13.299948 6.649974)
			(size 0.4572 0.4572)
			(layers "F.Cu" "F.Mask" "F.Paste")
			(net "Net_2887")
		)
		(pad "AM40" smd circle
			(at 14.249908 6.649974)
			(size 0.4572 0.4572)
			(layers "F.Cu" "F.Mask" "F.Paste")
			(net "GND")
		)
		(pad "AM41" smd circle
			(at 15.200122 6.649974)
			(size 0.4572 0.4572)
			(layers "F.Cu" "F.Mask" "F.Paste")
			(net "Net_2829")
		)
		(pad "AM42" smd circle
			(at 16.150082 6.649974)
			(size 0.4572 0.4572)
			(layers "F.Cu" "F.Mask" "F.Paste")
			(net "Net_2813")
		)
		(pad "AM43" smd circle
			(at 17.100042 6.649974)
			(size 0.4572 0.4572)
			(layers "F.Cu" "F.Mask" "F.Paste")
			(net "GND")
		)
		(pad "AM44" smd circle
			(at 18.050002 6.649974)
			(size 0.4572 0.4572)
			(layers "F.Cu" "F.Mask" "F.Paste")
			(net "GND")
		)
		(pad "AM45" smd circle
			(at 18.999962 6.649974)
			(size 0.4572 0.4572)
			(layers "F.Cu" "F.Mask" "F.Paste")
			(net "GND")
		)
		(pad "AM46" smd circle
			(at 19.949922 6.649974)
			(size 0.4572 0.4572)
			(layers "F.Cu" "F.Mask" "F.Paste")
			(net "GND")
		)
		(pad "AM47" smd circle
			(at 20.899882 6.649974)
			(size 0.4572 0.4572)
			(layers "F.Cu" "F.Mask" "F.Paste")
			(net "GND")
		)
		(pad "AM48" smd circle
			(at 21.850096 6.649974)
			(size 0.4572 0.4572)
			(layers "F.Cu" "F.Mask" "F.Paste")
			(net "Net_2797")
		)
		(pad "AM49" smd circle
			(at 22.800056 6.649974)
			(size 0.4572 0.4572)
			(layers "F.Cu" "F.Mask" "F.Paste")
			(net "Net_2781")
		)
		(pad "AN1" smd circle
			(at -22.800056 7.599934)
			(size 0.4572 0.4572)
			(layers "F.Cu" "F.Mask" "F.Paste")
			(net "GND")
		)
		(pad "AN2" smd circle
			(at -21.850096 7.599934)
			(size 0.4572 0.4572)
			(layers "F.Cu" "F.Mask" "F.Paste")
			(net "GND")
		)
		(pad "AN3" smd circle
			(at -20.899882 7.599934)
			(size 0.4572 0.4572)
			(layers "F.Cu" "F.Mask" "F.Paste")
			(net "P4E_PEX0_STN3_RX_DN<49>")
		)
		(pad "AN4" smd circle
			(at -19.949922 7.599934)
			(size 0.4572 0.4572)
			(layers "F.Cu" "F.Mask" "F.Paste")
			(net "P4E_PEX0_STN3_RX_DP<49>")
		)
		(pad "AN5" smd circle
			(at -18.999962 7.599934)
			(size 0.4572 0.4572)
			(layers "F.Cu" "F.Mask" "F.Paste")
			(net "GND")
		)
		(pad "AN6" smd circle
			(at -18.050002 7.599934)
			(size 0.4572 0.4572)
			(layers "F.Cu" "F.Mask" "F.Paste")
			(net "P4E_PEX0_STN3_TX_DN<49>")
		)
		(pad "AN7" smd circle
			(at -17.100042 7.599934)
			(size 0.4572 0.4572)
			(layers "F.Cu" "F.Mask" "F.Paste")
			(net "P4E_PEX0_STN3_TX_DP<49>")
		)
		(pad "AN8" smd circle
			(at -16.150082 7.599934)
			(size 0.4572 0.4572)
			(layers "F.Cu" "F.Mask" "F.Paste")
			(net "GND")
		)
		(pad "AN9" smd circle
			(at -15.200122 7.599934)
			(size 0.4572 0.4572)
			(layers "F.Cu" "F.Mask" "F.Paste")
			(net "GND")
		)
		(pad "AN10" smd circle
			(at -14.249908 7.599934)
			(size 0.4572 0.4572)
			(layers "F.Cu" "F.Mask" "F.Paste")
			(net "GND")
		)
		(pad "AN11" smd circle
			(at -13.299948 7.599934)
			(size 0.4572 0.4572)
			(layers "F.Cu" "F.Mask" "F.Paste")
			(net "GND")
		)
		(pad "AN12" smd circle
			(at -12.349988 7.599934)
			(size 0.4572 0.4572)
			(layers "F.Cu" "F.Mask" "F.Paste")
			(net "GND")
		)
		(pad "AN13" smd circle
			(at -11.400028 7.599934)
			(size 0.4572 0.4572)
			(layers "F.Cu" "F.Mask" "F.Paste")
			(net "GND")
		)
		(pad "AN14" smd circle
			(at -10.450068 7.599934)
			(size 0.4572 0.4572)
			(layers "F.Cu" "F.Mask" "F.Paste")
			(net "Net_491")
		)
		(pad "AN15" smd circle
			(at -9.500108 7.599934)
			(size 0.4572 0.4572)
			(layers "F.Cu" "F.Mask" "F.Paste")
			(net "GND")
		)
		(pad "AN16" smd circle
			(at -8.549894 7.599934)
			(size 0.4572 0.4572)
			(layers "F.Cu" "F.Mask" "F.Paste")
			(net "GND")
		)
		(pad "AN17" smd circle
			(at -7.599934 7.599934)
			(size 0.4572 0.4572)
			(layers "F.Cu" "F.Mask" "F.Paste")
			(net "GND")
		)
		(pad "AN18" smd circle
			(at -6.649974 7.599934)
			(size 0.4572 0.4572)
			(layers "F.Cu" "F.Mask" "F.Paste")
			(net "GND")
		)
		(pad "AN19" smd circle
			(at -5.700014 7.599934)
			(size 0.4572 0.4572)
			(layers "F.Cu" "F.Mask" "F.Paste")
			(net "GND")
		)
		(pad "AN20" smd circle
			(at -4.750054 7.599934)
			(size 0.4572 0.4572)
			(layers "F.Cu" "F.Mask" "F.Paste")
			(net "GND")
		)
		(pad "AN21" smd circle
			(at -3.800094 7.599934)
			(size 0.4572 0.4572)
			(layers "F.Cu" "F.Mask" "F.Paste")
			(net "GND")
		)
		(pad "AN22" smd circle
			(at -2.84988 7.599934)
			(size 0.4572 0.4572)
			(layers "F.Cu" "F.Mask" "F.Paste")
			(net "GND")
		)
		(pad "AN23" smd circle
			(at -1.89992 7.599934)
			(size 0.4572 0.4572)
			(layers "F.Cu" "F.Mask" "F.Paste")
			(net "GND")
		)
		(pad "AN24" smd circle
			(at -0.94996 7.599934)
			(size 0.4572 0.4572)
			(layers "F.Cu" "F.Mask" "F.Paste")
			(net "GND")
		)
		(pad "AN25" smd circle
			(at 0 7.599934)
			(size 0.4572 0.4572)
			(layers "F.Cu" "F.Mask" "F.Paste")
			(net "GND")
		)
		(pad "AN26" smd circle
			(at 0.94996 7.599934)
			(size 0.4572 0.4572)
			(layers "F.Cu" "F.Mask" "F.Paste")
			(net "GND")
		)
		(pad "AN27" smd circle
			(at 1.89992 7.599934)
			(size 0.4572 0.4572)
			(layers "F.Cu" "F.Mask" "F.Paste")
			(net "GND")
		)
		(pad "AN28" smd circle
			(at 2.84988 7.599934)
			(size 0.4572 0.4572)
			(layers "F.Cu" "F.Mask" "F.Paste")
			(net "GND")
		)
		(pad "AN29" smd circle
			(at 3.800094 7.599934)
			(size 0.4572 0.4572)
			(layers "F.Cu" "F.Mask" "F.Paste")
			(net "GND")
		)
		(pad "AN30" smd circle
			(at 4.750054 7.599934)
			(size 0.4572 0.4572)
			(layers "F.Cu" "F.Mask" "F.Paste")
			(net "GND")
		)
		(pad "AN31" smd circle
			(at 5.700014 7.599934)
			(size 0.4572 0.4572)
			(layers "F.Cu" "F.Mask" "F.Paste")
			(net "GND")
		)
		(pad "AN32" smd circle
			(at 6.649974 7.599934)
			(size 0.4572 0.4572)
			(layers "F.Cu" "F.Mask" "F.Paste")
			(net "GND")
		)
		(pad "AN33" smd circle
			(at 7.599934 7.599934)
			(size 0.4572 0.4572)
			(layers "F.Cu" "F.Mask" "F.Paste")
			(net "GND")
		)
		(pad "AN34" smd circle
			(at 8.549894 7.599934)
			(size 0.4572 0.4572)
			(layers "F.Cu" "F.Mask" "F.Paste")
			(net "GND")
		)
		(pad "AN35" smd circle
			(at 9.500108 7.599934)
			(size 0.4572 0.4572)
			(layers "F.Cu" "F.Mask" "F.Paste")
			(net "GND")
		)
		(pad "AN36" smd circle
			(at 10.450068 7.599934)
			(size 0.4572 0.4572)
			(layers "F.Cu" "F.Mask" "F.Paste")
			(net "Net_493")
		)
		(pad "AN37" smd circle
			(at 11.400028 7.599934)
			(size 0.4572 0.4572)
			(layers "F.Cu" "F.Mask" "F.Paste")
			(net "GND")
		)
		(pad "AN38" smd circle
			(at 12.349988 7.599934)
			(size 0.4572 0.4572)
			(layers "F.Cu" "F.Mask" "F.Paste")
			(net "Net_2878")
		)
		(pad "AN39" smd circle
			(at 13.299948 7.599934)
			(size 0.4572 0.4572)
			(layers "F.Cu" "F.Mask" "F.Paste")
			(net "Net_2845")
		)
		(pad "AN40" smd circle
			(at 14.249908 7.599934)
			(size 0.4572 0.4572)
			(layers "F.Cu" "F.Mask" "F.Paste")
			(net "GND")
		)
		(pad "AN41" smd circle
			(at 15.200122 7.599934)
			(size 0.4572 0.4572)
			(layers "F.Cu" "F.Mask" "F.Paste")
			(net "GND")
		)
		(pad "AN42" smd circle
			(at 16.150082 7.599934)
			(size 0.4572 0.4572)
			(layers "F.Cu" "F.Mask" "F.Paste")
			(net "GND")
		)
		(pad "AN43" smd circle
			(at 17.100042 7.599934)
			(size 0.4572 0.4572)
			(layers "F.Cu" "F.Mask" "F.Paste")
			(net "P5E_PEX0_STN0_TX_DP<0>")
		)
		(pad "AN44" smd circle
			(at 18.050002 7.599934)
			(size 0.4572 0.4572)
			(layers "F.Cu" "F.Mask" "F.Paste")
			(net "P5E_PEX0_STN0_TX_DN<0>")
		)
		(pad "AN45" smd circle
			(at 18.999962 7.599934)
			(size 0.4572 0.4572)
			(layers "F.Cu" "F.Mask" "F.Paste")
			(net "GND")
		)
		(pad "AN46" smd circle
			(at 19.949922 7.599934)
			(size 0.4572 0.4572)
			(layers "F.Cu" "F.Mask" "F.Paste")
			(net "P5E_PEX0_STN0_RX_DP<0>")
		)
		(pad "AN47" smd circle
			(at 20.899882 7.599934)
			(size 0.4572 0.4572)
			(layers "F.Cu" "F.Mask" "F.Paste")
			(net "P5E_PEX0_STN0_RX_DN<0>")
		)
		(pad "AN48" smd circle
			(at 21.850096 7.599934)
			(size 0.4572 0.4572)
			(layers "F.Cu" "F.Mask" "F.Paste")
			(net "GND")
		)
		(pad "AN49" smd circle
			(at 22.800056 7.599934)
			(size 0.4572 0.4572)
			(layers "F.Cu" "F.Mask" "F.Paste")
			(net "GND")
		)
		(pad "AP1" smd circle
			(at -22.800056 8.549894)
			(size 0.4572 0.4572)
			(layers "F.Cu" "F.Mask" "F.Paste")
			(net "Net_2710")
		)
		(pad "AP2" smd circle
			(at -21.850096 8.549894)
			(size 0.4572 0.4572)
			(layers "F.Cu" "F.Mask" "F.Paste")
			(net "Net_2724")
		)
		(pad "AP3" smd circle
			(at -20.899882 8.549894)
			(size 0.4572 0.4572)
			(layers "F.Cu" "F.Mask" "F.Paste")
			(net "GND")
		)
		(pad "AP4" smd circle
			(at -19.949922 8.549894)
			(size 0.4572 0.4572)
			(layers "F.Cu" "F.Mask" "F.Paste")
			(net "GND")
		)
		(pad "AP5" smd circle
			(at -18.999962 8.549894)
			(size 0.4572 0.4572)
			(layers "F.Cu" "F.Mask" "F.Paste")
			(net "GND")
		)
		(pad "AP6" smd circle
			(at -18.050002 8.549894)
			(size 0.4572 0.4572)
			(layers "F.Cu" "F.Mask" "F.Paste")
			(net "GND")
		)
		(pad "AP7" smd circle
			(at -17.100042 8.549894)
			(size 0.4572 0.4572)
			(layers "F.Cu" "F.Mask" "F.Paste")
			(net "GND")
		)
		(pad "AP8" smd circle
			(at -16.150082 8.549894)
			(size 0.4572 0.4572)
			(layers "F.Cu" "F.Mask" "F.Paste")
			(net "Net_2738")
		)
		(pad "AP9" smd circle
			(at -15.200122 8.549894)
			(size 0.4572 0.4572)
			(layers "F.Cu" "F.Mask" "F.Paste")
			(net "Net_2752")
		)
		(pad "AP10" smd circle
			(at -14.249908 8.549894)
			(size 0.4572 0.4572)
			(layers "F.Cu" "F.Mask" "F.Paste")
			(net "GND")
		)
		(pad "AP11" smd circle
			(at -13.299948 8.549894)
			(size 0.4572 0.4572)
			(layers "F.Cu" "F.Mask" "F.Paste")
			(net "GND")
		)
		(pad "AP12" smd circle
			(at -12.349988 8.549894)
			(size 0.4572 0.4572)
			(layers "F.Cu" "F.Mask" "F.Paste")
			(net "GND")
		)
		(pad "AP13" smd circle
			(at -11.400028 8.549894)
			(size 0.4572 0.4572)
			(layers "F.Cu" "F.Mask" "F.Paste")
			(net "GND")
		)
		(pad "AP14" smd circle
			(at -10.450068 8.549894)
			(size 0.4572 0.4572)
			(layers "F.Cu" "F.Mask" "F.Paste")
			(net "Net_486")
		)
		(pad "AP15" smd circle
			(at -9.500108 8.549894)
			(size 0.4572 0.4572)
			(layers "F.Cu" "F.Mask" "F.Paste")
			(net "GND")
		)
		(pad "AP16" smd circle
			(at -8.549894 8.549894)
			(size 0.4572 0.4572)
			(layers "F.Cu" "F.Mask" "F.Paste")
			(net "P1V25_SERDES_VDDPLL_PEX0")
		)
		(pad "AP17" smd circle
			(at -7.599934 8.549894)
			(size 0.4572 0.4572)
			(layers "F.Cu" "F.Mask" "F.Paste")
			(net "P1V25_SERDES_VDDPLL_PEX0")
		)
		(pad "AP18" smd circle
			(at -6.649974 8.549894)
			(size 0.4572 0.4572)
			(layers "F.Cu" "F.Mask" "F.Paste")
			(net "P1V25_SERDES_VDDPLL_PEX0")
		)
		(pad "AP19" smd circle
			(at -5.700014 8.549894)
			(size 0.4572 0.4572)
			(layers "F.Cu" "F.Mask" "F.Paste")
			(net "P1V25_SERDES_VDDPLL_PEX0")
		)
		(pad "AP20" smd circle
			(at -4.750054 8.549894)
			(size 0.4572 0.4572)
			(layers "F.Cu" "F.Mask" "F.Paste")
			(net "P1V25_SERDES_VDDPLL_PEX0")
		)
		(pad "AP21" smd circle
			(at -3.800094 8.549894)
			(size 0.4572 0.4572)
			(layers "F.Cu" "F.Mask" "F.Paste")
			(net "P1V25_SERDES_VDDPLL_PEX0")
		)
		(pad "AP22" smd circle
			(at -2.84988 8.549894)
			(size 0.4572 0.4572)
			(layers "F.Cu" "F.Mask" "F.Paste")
			(net "P1V25_SERDES_VDDPLL_PEX0")
		)
		(pad "AP23" smd circle
			(at -1.89992 8.549894)
			(size 0.4572 0.4572)
			(layers "F.Cu" "F.Mask" "F.Paste")
			(net "P1V25_SERDES_VDDPLL_PEX0")
		)
		(pad "AP24" smd circle
			(at -0.94996 8.549894)
			(size 0.4572 0.4572)
			(layers "F.Cu" "F.Mask" "F.Paste")
			(net "P1V25_SERDES_VDDPLL_PEX0")
		)
		(pad "AP25" smd circle
			(at 0 8.549894)
			(size 0.4572 0.4572)
			(layers "F.Cu" "F.Mask" "F.Paste")
			(net "P1V25_SERDES_VDDPLL_PEX0")
		)
		(pad "AP26" smd circle
			(at 0.94996 8.549894)
			(size 0.4572 0.4572)
			(layers "F.Cu" "F.Mask" "F.Paste")
			(net "P1V25_SERDES_VDDPLL_PEX0")
		)
		(pad "AP27" smd circle
			(at 1.89992 8.549894)
			(size 0.4572 0.4572)
			(layers "F.Cu" "F.Mask" "F.Paste")
			(net "P1V25_SERDES_VDDPLL_PEX0")
		)
		(pad "AP28" smd circle
			(at 2.84988 8.549894)
			(size 0.4572 0.4572)
			(layers "F.Cu" "F.Mask" "F.Paste")
			(net "P1V25_SERDES_VDDPLL_PEX0")
		)
	)
)
